# T6G (Grand Teton) — schematic netlist excerpt (pin names and nets, part order shuffled) for the footprints in the layout excerpt that follows; sources: Cadence DE-HDL packaged netlist, KiCad conversion of 04192023_DAF0TMB3IC0_F0TG_MB_C_brd_V02_OCP.brd

C22  Q_CAP  0.01UF 50V 10% EMPTY  pkg C0402  page 187 : A = U9_NR ; B = GND
C2671  Q_CAP  22UF 4V 20% X6S  pkg C0402  page 75 : A = PVDD18_S5_P1 ; B = GND

(kicad_pcb
	(version 20260206)
	(generator "pcbnew")
	(generator_version "10.0")
	(general
		(thickness 1.6)
		(legacy_teardrops no)
	)
	(paper "A4")
	(title_block
		(title "04192023_DAF0TMB3IC0_F0TG_MB_C_brd_V02_OCP.brd")
		(comment 1 "Grand Teton / footprints 2890-2891 of 8354")
	)
	(layers
		(0 "F.Cu" signal "TOP")
		(4 "In1.Cu" signal "GND")
		(6 "In2.Cu" signal "IN1")
		(8 "In3.Cu" signal "GND1")
		(10 "In4.Cu" signal "IN2")
		(12 "In5.Cu" signal "GND2")
		(14 "In6.Cu" signal "IN3")
		(16 "In7.Cu" signal "GND3")
		(18 "In8.Cu" signal "VCC")
		(20 "In9.Cu" signal "VCC1")
		(22 "In10.Cu" signal "GND4")
		(24 "In11.Cu" signal "IN4")
		(26 "In12.Cu" signal "GND5")
		(28 "In13.Cu" signal "IN5")
		(30 "In14.Cu" signal "GND6")
		(32 "In15.Cu" signal "IN6")
		(34 "In16.Cu" signal "GND7")
		(2 "B.Cu" signal "BOTTOM")
		(9 "F.Adhes" user "F.Adhesive")
		(11 "B.Adhes" user "B.Adhesive")
		(13 "F.Paste" user "Package Geometry/Pastemask Top")
		(15 "B.Paste" user "Package Geometry/Pastemask Bottom")
		(5 "F.SilkS" user "Ref Des/Silkscreen Top")
		(7 "B.SilkS" user "Ref Des/Silkscreen Bottom")
		(1 "F.Mask" user "Board Geometry/Soldermask Top")
		(3 "B.Mask" user "Board Geometry/Soldermask Bottom")
		(17 "Dwgs.User" user "User.Drawings")
		(19 "Cmts.User" user "User.Comments")
		(21 "Eco1.User" user "User.Eco1")
		(23 "Eco2.User" user "User.Eco2")
		(25 "Edge.Cuts" user "Board Geometry/Outline")
		(27 "Margin" user)
		(31 "F.CrtYd" user "Package Geometry/Place Bound Top")
		(29 "B.CrtYd" user "Package Geometry/Place Bound Bottom")
		(35 "F.Fab" user "Ref Des/Assembly Top")
		(33 "B.Fab" user "Ref Des/Assembly Bottom")
	)
	(footprint ""
		(layer "F.Cu")
		(at 105.960164 -255.555242)
		(property "Reference" "C2671"
			(at 0 0 0)
			(layer "F.SilkS")
			(hide yes)
			(effects
				(font
					(size 1.27 1.27)
				)
			)
		)
		(property "Value" ""
			(at 0 0 0)
			(layer "F.Fab")
			(effects
				(font
					(size 1.27 1.27)
				)
			)
		)
		(duplicate_pad_numbers_are_jumpers no)
		(fp_line
			(start -0.7874 -0.4064)
			(end 0.7874 -0.4064)
			(stroke
				(width 0.1524)
				(type default)
			)
			(layer "F.SilkS")
		)
		(fp_line
			(start -0.7874 0.4064)
			(end -0.7874 -0.4064)
			(stroke
				(width 0.1524)
				(type default)
			)
			(layer "F.SilkS")
		)
		(fp_line
			(start 0.7874 -0.4064)
			(end 0.7874 0.4064)
			(stroke
				(width 0.1524)
				(type default)
			)
			(layer "F.SilkS")
		)
		(fp_line
			(start 0.7874 0.4064)
			(end -0.7874 0.4064)
			(stroke
				(width 0.1524)
				(type default)
			)
			(layer "F.SilkS")
		)
		(fp_line
			(start -0.67945 -0.305054)
			(end -0.12065 -0.305054)
			(stroke
				(width 0.1)
				(type default)
			)
			(layer "F.Fab")
		)
		(fp_line
			(start -0.67945 0.3048)
			(end -0.67945 -0.305054)
			(stroke
				(width 0.1)
				(type default)
			)
			(layer "F.Fab")
		)
		(fp_line
			(start -0.12065 -0.305054)
			(end -0.12065 -0.2794)
			(stroke
				(width 0.1)
				(type default)
			)
			(layer "F.Fab")
		)
		(fp_line
			(start -0.12065 -0.2794)
			(end 0.12065 -0.2794)
			(stroke
				(width 0.1)
				(type default)
			)
			(layer "F.Fab")
		)
		(fp_line
			(start -0.12065 0.2794)
			(end -0.12065 0.3048)
			(stroke
				(width 0.1)
				(type default)
			)
			(layer "F.Fab")
		)
		(fp_line
			(start -0.12065 0.3048)
			(end -0.67945 0.3048)
			(stroke
				(width 0.1)
				(type default)
			)
			(layer "F.Fab")
		)
		(fp_line
			(start 0.120396 0.2794)
			(end -0.12065 0.2794)
			(stroke
				(width 0.1)
				(type default)
			)
			(layer "F.Fab")
		)
		(fp_line
			(start 0.120396 0.3048)
			(end 0.120396 0.2794)
			(stroke
				(width 0.1)
				(type default)
			)
			(layer "F.Fab")
		)
		(fp_line
			(start 0.12065 -0.3048)
			(end 0.67945 -0.3048)
			(stroke
				(width 0.1)
				(type default)
			)
			(layer "F.Fab")
		)
		(fp_line
			(start 0.12065 -0.2794)
			(end 0.12065 -0.3048)
			(stroke
				(width 0.1)
				(type default)
			)
			(layer "F.Fab")
		)
		(fp_line
			(start 0.67945 -0.3048)
			(end 0.67945 0.3048)
			(stroke
				(width 0.1)
				(type default)
			)
			(layer "F.Fab")
		)
		(fp_line
			(start 0.67945 0.3048)
			(end 0.120396 0.3048)
			(stroke
				(width 0.1)
				(type default)
			)
			(layer "F.Fab")
		)
		(pad "1" smd circle
			(at -0.40005 0)
			(size 0 0)
			(layers "F.Cu" "F.Mask" "F.Paste")
			(net "PVDD18_S5_P1")
		)
		(pad "2" smd circle
			(at 0.40005 0)
			(size 0 0)
			(layers "F.Cu" "F.Mask" "F.Paste")
			(net "GND")
		)
	)
	(footprint ""
		(layer "F.Cu")
		(at 307.741574 -24.090884)
		(property "Reference" "C22"
			(at 0 0 0)
			(layer "F.SilkS")
			(hide yes)
			(effects
				(font
					(size 1.27 1.27)
				)
			)
		)
		(property "Value" ""
			(at 0 0 0)
			(layer "F.Fab")
			(effects
				(font
					(size 1.27 1.27)
				)
			)
		)
		(duplicate_pad_numbers_are_jumpers no)
		(fp_line
			(start -0.7874 -0.4064)
			(end 0.7874 -0.4064)
			(stroke
				(width 0.1524)
				(type default)
			)
			(layer "F.SilkS")
		)
		(fp_line
			(start -0.7874 0.4064)
			(end -0.7874 -0.4064)
			(stroke
				(width 0.1524)
				(type default)
			)
			(layer "F.SilkS")
		)
		(fp_line
			(start 0.7874 -0.4064)
			(end 0.7874 0.4064)
			(stroke
				(width 0.1524)
				(type default)
			)
			(layer "F.SilkS")
		)
		(fp_line
			(start 0.7874 0.4064)
			(end -0.7874 0.4064)
			(stroke
				(width 0.1524)
				(type default)
			)
			(layer "F.SilkS")
		)
		(fp_line
			(start -0.67945 -0.305054)
			(end -0.12065 -0.305054)
			(stroke
				(width 0.1)
				(type default)
			)
			(layer "F.Fab")
		)
		(fp_line
			(start -0.67945 0.3048)
			(end -0.67945 -0.305054)
			(stroke
				(width 0.1)
				(type default)
			)
			(layer "F.Fab")
		)
		(fp_line
			(start -0.12065 -0.305054)
			(end -0.12065 -0.2794)
			(stroke
				(width 0.1)
				(type default)
			)
			(layer "F.Fab")
		)
		(fp_line
			(start -0.12065 -0.2794)
			(end 0.12065 -0.2794)
			(stroke
				(width 0.1)
				(type default)
			)
			(layer "F.Fab")
		)
		(fp_line
			(start -0.12065 0.2794)
			(end -0.12065 0.3048)
			(stroke
				(width 0.1)
				(type default)
			)
			(layer "F.Fab")
		)
		(fp_line
			(start -0.12065 0.3048)
			(end -0.67945 0.3048)
			(stroke
				(width 0.1)
				(type default)
			)
			(layer "F.Fab")
		)
		(fp_line
			(start 0.120396 0.2794)
			(end -0.12065 0.2794)
			(stroke
				(width 0.1)
				(type default)
			)
			(layer "F.Fab")
		)
		(fp_line
			(start 0.120396 0.3048)
			(end 0.120396 0.2794)
			(stroke
				(width 0.1)
				(type default)
			)
			(layer "F.Fab")
		)
		(fp_line
			(start 0.12065 -0.3048)
			(end 0.67945 -0.3048)
			(stroke
				(width 0.1)
				(type default)
			)
			(layer "F.Fab")
		)
		(fp_line
			(start 0.12065 -0.2794)
			(end 0.12065 -0.3048)
			(stroke
				(width 0.1)
				(type default)
			)
			(layer "F.Fab")
		)
		(fp_line
			(start 0.67945 -0.3048)
			(end 0.67945 0.3048)
			(stroke
				(width 0.1)
				(type default)
			)
			(layer "F.Fab")
		)
		(fp_line
			(start 0.67945 0.3048)
			(end 0.120396 0.3048)
			(stroke
				(width 0.1)
				(type default)
			)
			(layer "F.Fab")
		)
		(pad "1" smd circle
			(at -0.40005 0)
			(size 0 0)
			(layers "F.Cu" "F.Mask" "F.Paste")
			(net "U9_NR")
		)
		(pad "2" smd circle
			(at 0.40005 0)
			(size 0 0)
			(layers "F.Cu" "F.Mask" "F.Paste")
			(net "GND")
		)
	)
)
